#ISCELL
  logical_power design_note *
  *
#ISCELL
  mstr_misc dns *
  *
#ISCELL
  pure_quanta quanta_title_block_c *
  *
#CELL
  pure_quanta 9qxl2001bnhgi8 *
  page195_i119
#ISCELL
  standard offpage *
  page195_i120
#ISCELL
  standard offpage *
  page195_i121
#ISCELL
  standard offpage *
  page195_i122
#ISCELL
  standard offpage *
  page195_i123
#ISCELL
  standard offpage *
  page195_i126
#ISCELL
  standard offpage *
  page195_i127
#ISCELL
  standard offpage *
  page195_i128
#ISCELL
  standard offpage *
  page195_i129
#ISCELL
  standard offpage *
  page195_i150
#ISCELL
  standard offpage *
  page195_i151
#ISCELL
  standard offpage *
  page195_i154
#CELL
  pure_quanta q_res *
  page195_i156
#ISCELL
  standard offpage *
  page195_i157
#ISCELL
  logical_power universal_power *
  page195_i158
#ISCELL
  logical_power universal_power *
  page195_i159
#ISCELL
  logical_power universal_power *
  page195_i160
#ISCELL
  logical_power universal_power *
  page195_i161
#CELL
  pure_quanta q_res *
  page195_i162
#CELL
  pure_quanta q_res *
  page195_i163
#CELL
  pure_quanta q_cap *
  page195_i164
#CELL
  pure_quanta q_cap *
  page195_i165
#ISCELL
  logical_power universal_power *
  page195_i166
#CELL
  pure_quanta q_cap *
  page195_i167
#CELL
  pure_quanta q_cap *
  page195_i168
#ISCELL
  logical_power universal_power *
  page195_i169
#CELL
  pure_quanta q_inductor *
  page195_i170
#CELL
  pure_quanta q_cap *
  page195_i171
#CELL
  pure_quanta q_cap *
  page195_i172
#CELL
  pure_quanta q_cap *
  page195_i173
#CELL
  pure_quanta q_cap *
  page195_i174
#ISCELL
  logical_power universal_power *
  page195_i175
#ISCELL
  logical_power universal_power *
  page195_i176
#CELL
  pure_quanta q_inductor *
  page195_i177
#CELL
  pure_quanta q_res *
  page195_i178
#CELL
  pure_quanta q_res *
  page195_i179
#ISCELL
  logical_power universal_power *
  page195_i183
#CELL
  pure_quanta q_res *
  page195_i185
#CELL
  pure_quanta q_res *
  page195_i187
#ISCELL
  standard offpage *
  page195_i188
#ISCELL
  standard offpage *
  page195_i189
#ISCELL
  standard offpage *
  page195_i190
#ISCELL
  standard offpage *
  page195_i191
#ISCELL
  standard offpage *
  page195_i192
#CELL
  pure_quanta q_res *
  page195_i194
#ISCELL
  logical_power universal_power *
  page195_i195
#CELL
  pure_quanta q_res *
  page195_i197
#CELL
  pure_quanta q_res *
  page195_i199
#ISCELL
  standard offpage *
  page195_i200
#CELL
  pure_quanta q_res *
  page195_i304
#ISCELL
  standard offpage *
  page195_i381
#ISCELL
  standard offpage *
  page195_i382
#ISCELL
  standard offpage *
  page195_i383
#ISCELL
  standard offpage *
  page195_i384
#ISCELL
  standard offpage *
  page195_i385
#ISCELL
  standard offpage *
  page195_i386
#ISCELL
  standard offpage *
  page195_i387
#ISCELL
  standard offpage *
  page195_i388
#ISCELL
  standard offpage *
  page195_i409
#ISCELL
  standard offpage *
  page195_i410
#CELL
  pure_quanta q_cap *
  page195_i419
#ISCELL
  logical_power universal_gnd *
  page195_i432
#ISCELL
  logical_power universal_gnd *
  page195_i433
#ISCELL
  logical_power universal_gnd *
  page195_i434
#ISCELL
  logical_power universal_gnd *
  page195_i435
#ISCELL
  logical_power universal_gnd *
  page195_i436
#ISCELL
  logical_power universal_gnd *
  page195_i437
#ISCELL
  logical_power universal_gnd *
  page195_i438
#ISCELL
  logical_power universal_gnd *
  page195_i439
#CELL
  pure_quanta q_res *
  page195_i487
#ISCELL
  standard offpage *
  page195_i488
#ISCELL
  standard offpage *
  page195_i502
#ISCELL
  standard offpage *
  page195_i503
#ISCELL
  standard offpage *
  page195_i504
#ISCELL
  standard offpage *
  page195_i505
#ISCELL
  standard offpage *
  page195_i506
#ISCELL
  standard offpage *
  page195_i507
#ISCELL
  standard offpage *
  page195_i508
#ISCELL
  standard offpage *
  page195_i509
#ISCELL
  standard offpage *
  page195_i519
#ISCELL
  standard offpage *
  page195_i520
#ISCELL
  standard offpage *
  page195_i523
#ISCELL
  standard offpage *
  page195_i524
#ISCELL
  standard offpage *
  page195_i525
#ISCELL
  standard offpage *
  page195_i528
#ISCELL
  standard offpage *
  page195_i529
#ISCELL
  standard offpage *
  page195_i530
#ISCELL
  standard offpage *
  page195_i531
#ISCELL
  standard offpage *
  page195_i532
#CELL
  pure_quanta q_res *
  page195_i534
#CELL
  pure_quanta q_res *
  page195_i535
#CELL
  pure_quanta q_res *
  page195_i536
#CELL
  pure_quanta q_res *
  page195_i537
#ISCELL
  standard offpage *
  page195_i538
#CELL
  pure_quanta q_res *
  page195_i539
#CELL
  pure_quanta q_res *
  page195_i540
#ISCELL
  logical_power universal_power *
  page195_i541
